(kicad_pcb
	(version 20260206)
	(generator "pcbnew")
	(generator_version "10.0")
	(general
		(thickness 1.6)
		(legacy_teardrops no)
	)
	(paper "A4")
	(title_block
		(title "dpb — 14545-sa.0730WZS0815.brd")
		(comment 1 "Honey Badger (Wiwynn) / footprints 1007-1013 of 1066")
	)
	(layers
		(0 "F.Cu" signal "TOP")
		(4 "In1.Cu" signal "L2GND")
		(6 "In2.Cu" signal "L3")
		(8 "In3.Cu" signal "L4VCC")
		(10 "In4.Cu" signal "L5VCC")
		(12 "In5.Cu" signal "L6")
		(14 "In6.Cu" signal "L7GND")
		(2 "B.Cu" signal "BOTTOM")
		(9 "F.Adhes" user "F.Adhesive")
		(11 "B.Adhes" user "B.Adhesive")
		(13 "F.Paste" user "Package Geometry/Pastemask Top")
		(15 "B.Paste" user "Package Geometry/Pastemask Bottom")
		(5 "F.SilkS" user "Ref Des/Silkscreen Top")
		(7 "B.SilkS" user "Ref Des/Silkscreen Bottom")
		(1 "F.Mask" user "Board Geometry/Soldermask Top")
		(3 "B.Mask" user "Board Geometry/Soldermask Bottom")
		(17 "Dwgs.User" user "User.Drawings")
		(19 "Cmts.User" user "User.Comments")
		(21 "Eco1.User" user "User.Eco1")
		(23 "Eco2.User" user "User.Eco2")
		(25 "Edge.Cuts" user "Board Geometry/Outline")
		(27 "Margin" user)
		(31 "F.CrtYd" user "Package Geometry/Place Bound Top")
		(29 "B.CrtYd" user "Package Geometry/Place Bound Bottom")
		(35 "F.Fab" user "Ref Des/Assembly Top")
		(33 "B.Fab" user "Ref Des/Assembly Bottom")
	)
	(footprint ""
		(layer "F.Cu")
		(at 16.255746 -476.6437)
		(property "Reference" "PC39"
			(at 0 0 0)
			(layer "F.SilkS")
			(hide yes)
			(effects
				(font
					(size 1.27 1.27)
				)
			)
		)
		(property "Value" "SC10U16V6KX-2GP"
			(at -0.0762 -5.1308 0)
			(unlocked yes)
			(layer "F.Fab")
			(hide yes)
			(effects
				(font
					(size 1.016 1.016)
					(thickness 0.1524)
				)
			)
		)
		(property "Device Type" "C1206H71"
			(at -0.127 -6.6548 0)
			(unlocked yes)
			(layer "F.Fab")
			(hide yes)
			(effects
				(font
					(size 1.016 1.016)
					(thickness 0.1524)
				)
			)
		)
		(duplicate_pad_numbers_are_jumpers no)
		(fp_line
			(start -1.016 -2.2352)
			(end 1.016 -2.2352)
			(stroke
				(width 0.1524)
				(type default)
			)
			(layer "F.SilkS")
		)
		(fp_line
			(start -1.016 -0.8382)
			(end -1.016 -2.2352)
			(stroke
				(width 0.1524)
				(type default)
			)
			(layer "F.SilkS")
		)
		(fp_line
			(start -1.016 2.2352)
			(end -1.016 0.8382)
			(stroke
				(width 0.1524)
				(type default)
			)
			(layer "F.SilkS")
		)
		(fp_line
			(start 1.016 -2.2352)
			(end 1.016 -0.8382)
			(stroke
				(width 0.1524)
				(type default)
			)
			(layer "F.SilkS")
		)
		(fp_line
			(start 1.016 0.8382)
			(end 1.016 2.2352)
			(stroke
				(width 0.1524)
				(type default)
			)
			(layer "F.SilkS")
		)
		(fp_line
			(start 1.016 2.2352)
			(end -1.016 2.2352)
			(stroke
				(width 0.1524)
				(type default)
			)
			(layer "F.SilkS")
		)
		(fp_rect
			(start -1.0922 2.3114)
			(end 1.0922 -2.3114)
			(stroke
				(width 0)
				(type default)
			)
			(fill no)
			(layer "F.CrtYd")
		)
		(fp_poly
			(pts
				(xy 1.0922 -2.3114) (xy 1.0922 2.3114) (xy -1.0922 2.3114) (xy -1.0922 -2.3114)
			)
			(stroke
				(width 0)
				(type default)
			)
			(fill no)
			(layer "F.Fab")
		)
		(pad "1" smd rect
			(at 0 -1.397)
			(size 1.651 1.27)
			(layers "F.Cu" "F.Mask" "F.Paste")
			(net "P5VC")
		)
		(pad "2" smd rect
			(at 0 1.397)
			(size 1.651 1.27)
			(layers "F.Cu" "F.Mask" "F.Paste")
			(net "GND")
		)
	)
	(footprint ""
		(layer "F.Cu")
		(at 218.142058 -373.201184 -90)
		(property "Reference" "C121"
			(at 0 0 270)
			(layer "F.SilkS")
			(hide yes)
			(effects
				(font
					(size 1.27 1.27)
				)
			)
		)
		(property "Value" "SCD01U50V2KX-1GP"
			(at 1.1811 -2.7051 270)
			(unlocked yes)
			(layer "F.Fab")
			(hide yes)
			(effects
				(font
					(size 1.016 1.016)
					(thickness 0.1524)
				)
			)
		)
		(property "Device Type" "C402H22"
			(at 1.1811 -4.2291 270)
			(unlocked yes)
			(layer "F.Fab")
			(hide yes)
			(effects
				(font
					(size 1.016 1.016)
					(thickness 0.1524)
				)
			)
		)
		(duplicate_pad_numbers_are_jumpers no)
		(fp_rect
			(start -0.4318 0.9525)
			(end 0.4318 -0.9525)
			(stroke
				(width 0)
				(type default)
			)
			(fill no)
			(layer "F.CrtYd")
		)
		(fp_rect
			(start -0.4318 0.9525)
			(end 0.4318 -0.9525)
			(stroke
				(width 0)
				(type default)
			)
			(fill no)
			(layer "F.Fab")
		)
		(pad "1" smd custom
			(at 0 -0.4445 270)
			(size 0.1524 0.1524)
			(layers "F.Cu" "F.Mask" "F.Paste")
			(net "SAS2X28_DRIVE_RX_P_B1")
			(options
				(clearance outline)
				(anchor circle)
			)
			(primitives
				(gr_poly
					(pts
						(arc
							(start 0.3048 -0.2032)
							(mid 0.275042 -0.275042)
							(end 0.2032 -0.3048)
						)
						(arc
							(start -0.2032 -0.3048)
							(mid -0.275042 -0.275042)
							(end -0.3048 -0.2032)
						)
						(arc
							(start -0.3048 0.2032)
							(mid -0.275042 0.275042)
							(end -0.2032 0.3048)
						)
						(arc
							(start 0.2032 0.3048)
							(mid 0.275042 0.275042)
							(end 0.3048 0.2032)
						)
					)
					(width 0)
					(fill yes)
				)
			)
		)
		(pad "2" smd custom
			(at 0 0.4445 270)
			(size 0.1524 0.1524)
			(layers "F.Cu" "F.Mask" "F.Paste")
			(net "SAS2X28_B_HDD1_RX_+")
			(options
				(clearance outline)
				(anchor circle)
			)
			(primitives
				(gr_poly
					(pts
						(arc
							(start 0.3048 -0.2032)
							(mid 0.275042 -0.275042)
							(end 0.2032 -0.3048)
						)
						(arc
							(start -0.2032 -0.3048)
							(mid -0.275042 -0.275042)
							(end -0.3048 -0.2032)
						)
						(arc
							(start -0.3048 0.2032)
							(mid -0.275042 0.275042)
							(end -0.2032 0.3048)
						)
						(arc
							(start 0.2032 0.3048)
							(mid 0.275042 0.275042)
							(end 0.3048 0.2032)
						)
					)
					(width 0)
					(fill yes)
				)
			)
		)
	)
	(footprint ""
		(layer "F.Cu")
		(at 29.844746 -332.3717)
		(property "Reference" "U34"
			(at 0 0 0)
			(layer "F.SilkS")
			(hide yes)
			(effects
				(font
					(size 1.27 1.27)
				)
			)
		)
		(property "Value" "74LVC1G08GW-1-GP"
			(at -2.3368 -8.6868 0)
			(unlocked yes)
			(layer "F.Fab")
			(hide yes)
			(effects
				(font
					(size 1.016 1.016)
					(thickness 0.1524)
				)
			)
		)
		(property "Device Type" "SC70-5H44"
			(at -2.3114 -10.414 0)
			(unlocked yes)
			(layer "F.Fab")
			(hide yes)
			(effects
				(font
					(size 1.016 1.016)
					(thickness 0.1524)
				)
			)
		)
		(duplicate_pad_numbers_are_jumpers no)
		(fp_line
			(start -1.27 -1.7018)
			(end 1.27 -1.7018)
			(stroke
				(width 0.1524)
				(type default)
			)
			(layer "F.SilkS")
		)
		(fp_line
			(start -1.27 1.7018)
			(end -1.27 -1.7018)
			(stroke
				(width 0.1524)
				(type default)
			)
			(layer "F.SilkS")
		)
		(fp_line
			(start 0.6604 -1.8034)
			(end 1.3843 -1.8034)
			(stroke
				(width 0.3302)
				(type default)
			)
			(layer "F.SilkS")
		)
		(fp_line
			(start 1.27 -1.7018)
			(end 1.27 1.7018)
			(stroke
				(width 0.1524)
				(type default)
			)
			(layer "F.SilkS")
		)
		(fp_line
			(start 1.27 1.7018)
			(end -1.27 1.7018)
			(stroke
				(width 0.1524)
				(type default)
			)
			(layer "F.SilkS")
		)
		(fp_line
			(start 1.3843 -1.8034)
			(end 1.3843 -1.1176)
			(stroke
				(width 0.3302)
				(type default)
			)
			(layer "F.SilkS")
		)
		(fp_rect
			(start -1.524 1.9558)
			(end 1.524 -1.9558)
			(stroke
				(width 0)
				(type default)
			)
			(fill no)
			(layer "F.CrtYd")
		)
		(fp_poly
			(pts
				(xy -1.524 -1.9558) (xy 1.524 -1.9558) (xy 1.524 1.9558) (xy -1.524 1.9558)
			)
			(stroke
				(width 0)
				(type default)
			)
			(fill no)
			(layer "F.Fab")
		)
		(pad "1" smd rect
			(at 0.65024 -0.8255)
			(size 0.4064 1.2192)
			(layers "F.Cu" "F.Mask" "F.Paste")
			(net "SAS2X28_B_HDD11_FLT")
		)
		(pad "2" smd rect
			(at 0 -0.8255)
			(size 0.4064 1.2192)
			(layers "F.Cu" "F.Mask" "F.Paste")
			(net "SAS2X28_A_HDD11_FLT")
		)
		(pad "3" smd rect
			(at -0.65024 -0.8255)
			(size 0.4064 1.2192)
			(layers "F.Cu" "F.Mask" "F.Paste")
			(net "GND")
		)
		(pad "4" smd rect
			(at -0.65024 0.8255)
			(size 0.4064 1.2192)
			(layers "F.Cu" "F.Mask" "F.Paste")
			(net "FLT_HDD11_DRIVE")
		)
		(pad "5" smd rect
			(at 0.65024 0.8255)
			(size 0.4064 1.2192)
			(layers "F.Cu" "F.Mask" "F.Paste")
			(net "P3V3")
		)
	)
	(footprint ""
		(layer "F.Cu")
		(at 191.897 -498.094 90)
		(property "Reference" "R108"
			(at 0 0 90)
			(layer "F.SilkS")
			(hide yes)
			(effects
				(font
					(size 1.27 1.27)
				)
			)
		)
		(property "Value" "4K7R2J-2-GP"
			(at 0.064008 -3.993896 90)
			(unlocked yes)
			(layer "F.Fab")
			(hide yes)
			(effects
				(font
					(size 1.016 1.016)
					(thickness 0.1524)
				)
			)
		)
		(property "Device Type" "R402H16"
			(at 0.064008 -5.517896 90)
			(unlocked yes)
			(layer "F.Fab")
			(hide yes)
			(effects
				(font
					(size 1.016 1.016)
					(thickness 0.1524)
				)
			)
		)
		(duplicate_pad_numbers_are_jumpers no)
		(fp_line
			(start 0.508 -0.9398)
			(end -0.508 -0.9398)
			(stroke
				(width 0.1524)
				(type default)
			)
			(layer "F.SilkS")
		)
		(fp_line
			(start -0.508 -0.9398)
			(end -0.508 0.9398)
			(stroke
				(width 0.1524)
				(type default)
			)
			(layer "F.SilkS")
		)
		(fp_rect
			(start -0.508 0.9398)
			(end 0.508 -0.9398)
			(stroke
				(width 0)
				(type default)
			)
			(fill no)
			(layer "F.CrtYd")
		)
		(fp_rect
			(start -0.508 0.9398)
			(end 0.508 -0.9398)
			(stroke
				(width 0)
				(type default)
			)
			(fill no)
			(layer "F.Fab")
		)
		(pad "1" smd custom
			(at 0 -0.4445 90)
			(size 0.1397 0.1397)
			(layers "F.Cu" "F.Mask" "F.Paste")
			(net "P12V")
			(options
				(clearance outline)
				(anchor circle)
			)
			(primitives
				(gr_poly
					(pts
						(arc
							(start -0.1778 -0.2794)
							(mid -0.249642 -0.249642)
							(end -0.2794 -0.1778)
						)
						(arc
							(start -0.2794 0.1778)
							(mid -0.249642 0.249642)
							(end -0.1778 0.2794)
						)
						(arc
							(start 0.1778 0.2794)
							(mid 0.249642 0.249642)
							(end 0.2794 0.1778)
						)
						(arc
							(start 0.2794 -0.1778)
							(mid 0.249642 -0.249642)
							(end 0.1778 -0.2794)
						)
					)
					(width 0)
					(fill yes)
				)
			)
		)
		(pad "2" smd custom
			(at 0 0.4445 90)
			(size 0.1397 0.1397)
			(layers "F.Cu" "F.Mask" "F.Paste")
			(net "SW_HDD0_R")
			(options
				(clearance outline)
				(anchor circle)
			)
			(primitives
				(gr_poly
					(pts
						(arc
							(start -0.1778 -0.2794)
							(mid -0.249642 -0.249642)
							(end -0.2794 -0.1778)
						)
						(arc
							(start -0.2794 0.1778)
							(mid -0.249642 0.249642)
							(end -0.1778 0.2794)
						)
						(arc
							(start 0.1778 0.2794)
							(mid 0.249642 0.249642)
							(end 0.2794 0.1778)
						)
						(arc
							(start 0.2794 -0.1778)
							(mid 0.249642 -0.249642)
							(end 0.1778 -0.2794)
						)
					)
					(width 0)
					(fill yes)
				)
			)
		)
	)
	(footprint ""
		(layer "F.Cu")
		(at 45.212 -106.807 90)
		(property "Reference" "R561"
			(at 0 0 90)
			(layer "F.SilkS")
			(hide yes)
			(effects
				(font
					(size 1.27 1.27)
				)
			)
		)
		(property "Value" "200KR2F-L-GP"
			(at 0.064008 -3.993896 90)
			(unlocked yes)
			(layer "F.Fab")
			(hide yes)
			(effects
				(font
					(size 1.016 1.016)
					(thickness 0.1524)
				)
			)
		)
		(property "Device Type" "R402H16"
			(at 0.064008 -5.517896 90)
			(unlocked yes)
			(layer "F.Fab")
			(hide yes)
			(effects
				(font
					(size 1.016 1.016)
					(thickness 0.1524)
				)
			)
		)
		(duplicate_pad_numbers_are_jumpers no)
		(fp_line
			(start 0.508 -0.9398)
			(end -0.508 -0.9398)
			(stroke
				(width 0.1524)
				(type default)
			)
			(layer "F.SilkS")
		)
		(fp_line
			(start -0.508 -0.9398)
			(end -0.508 0.9398)
			(stroke
				(width 0.1524)
				(type default)
			)
			(layer "F.SilkS")
		)
		(fp_rect
			(start -0.508 0.9398)
			(end 0.508 -0.9398)
			(stroke
				(width 0)
				(type default)
			)
			(fill no)
			(layer "F.CrtYd")
		)
		(fp_rect
			(start -0.508 0.9398)
			(end 0.508 -0.9398)
			(stroke
				(width 0)
				(type default)
			)
			(fill no)
			(layer "F.Fab")
		)
		(pad "1" smd custom
			(at 0 -0.4445 90)
			(size 0.1397 0.1397)
			(layers "F.Cu" "F.Mask" "F.Paste")
			(net "SW_HDD13_R")
			(options
				(clearance outline)
				(anchor circle)
			)
			(primitives
				(gr_poly
					(pts
						(arc
							(start -0.1778 -0.2794)
							(mid -0.249642 -0.249642)
							(end -0.2794 -0.1778)
						)
						(arc
							(start -0.2794 0.1778)
							(mid -0.249642 0.249642)
							(end -0.1778 0.2794)
						)
						(arc
							(start 0.1778 0.2794)
							(mid 0.249642 0.249642)
							(end 0.2794 0.1778)
						)
						(arc
							(start 0.2794 -0.1778)
							(mid 0.249642 -0.249642)
							(end 0.1778 -0.2794)
						)
					)
					(width 0)
					(fill yes)
				)
			)
		)
		(pad "2" smd custom
			(at 0 0.4445 90)
			(size 0.1397 0.1397)
			(layers "F.Cu" "F.Mask" "F.Paste")
			(net "SW_HDD13_N")
			(options
				(clearance outline)
				(anchor circle)
			)
			(primitives
				(gr_poly
					(pts
						(arc
							(start -0.1778 -0.2794)
							(mid -0.249642 -0.249642)
							(end -0.2794 -0.1778)
						)
						(arc
							(start -0.2794 0.1778)
							(mid -0.249642 0.249642)
							(end -0.1778 0.2794)
						)
						(arc
							(start 0.1778 0.2794)
							(mid 0.249642 0.249642)
							(end 0.2794 0.1778)
						)
						(arc
							(start 0.2794 -0.1778)
							(mid 0.249642 -0.249642)
							(end 0.1778 -0.2794)
						)
					)
					(width 0)
					(fill yes)
				)
			)
		)
	)
	(footprint ""
		(layer "F.Cu")
		(at 232.257346 -141.6812 -90)
		(property "Reference" "R491"
			(at 0 0 270)
			(layer "F.SilkS")
			(hide yes)
			(effects
				(font
					(size 1.27 1.27)
				)
			)
		)
		(property "Value" "1KR2F-3-GP"
			(at 0.064008 -3.993896 270)
			(unlocked yes)
			(layer "F.Fab")
			(hide yes)
			(effects
				(font
					(size 1.016 1.016)
					(thickness 0.1524)
				)
			)
		)
		(property "Device Type" "R402H16"
			(at 0.064008 -5.517896 270)
			(unlocked yes)
			(layer "F.Fab")
			(hide yes)
			(effects
				(font
					(size 1.016 1.016)
					(thickness 0.1524)
				)
			)
		)
		(duplicate_pad_numbers_are_jumpers no)
		(fp_line
			(start -0.508 -0.9398)
			(end -0.508 0.9398)
			(stroke
				(width 0.1524)
				(type default)
			)
			(layer "F.SilkS")
		)
		(fp_line
			(start 0.508 -0.9398)
			(end -0.508 -0.9398)
			(stroke
				(width 0.1524)
				(type default)
			)
			(layer "F.SilkS")
		)
		(fp_rect
			(start -0.508 0.9398)
			(end 0.508 -0.9398)
			(stroke
				(width 0)
				(type default)
			)
			(fill no)
			(layer "F.CrtYd")
		)
		(fp_rect
			(start -0.508 0.9398)
			(end 0.508 -0.9398)
			(stroke
				(width 0)
				(type default)
			)
			(fill no)
			(layer "F.Fab")
		)
		(pad "1" smd custom
			(at 0 -0.4445 270)
			(size 0.1397 0.1397)
			(layers "F.Cu" "F.Mask" "F.Paste")
			(net "FLT_HDD3_B")
			(options
				(clearance outline)
				(anchor circle)
			)
			(primitives
				(gr_poly
					(pts
						(arc
							(start -0.1778 -0.2794)
							(mid -0.249642 -0.249642)
							(end -0.2794 -0.1778)
						)
						(arc
							(start -0.2794 0.1778)
							(mid -0.249642 0.249642)
							(end -0.1778 0.2794)
						)
						(arc
							(start 0.1778 0.2794)
							(mid 0.249642 0.249642)
							(end 0.2794 0.1778)
						)
						(arc
							(start 0.2794 -0.1778)
							(mid 0.249642 -0.249642)
							(end 0.1778 -0.2794)
						)
					)
					(width 0)
					(fill yes)
				)
			)
		)
		(pad "2" smd custom
			(at 0 0.4445 270)
			(size 0.1397 0.1397)
			(layers "F.Cu" "F.Mask" "F.Paste")
			(net "FLT_HDD3_DRIVE")
			(options
				(clearance outline)
				(anchor circle)
			)
			(primitives
				(gr_poly
					(pts
						(arc
							(start -0.1778 -0.2794)
							(mid -0.249642 -0.249642)
							(end -0.2794 -0.1778)
						)
						(arc
							(start -0.2794 0.1778)
							(mid -0.249642 0.249642)
							(end -0.1778 0.2794)
						)
						(arc
							(start 0.1778 0.2794)
							(mid 0.249642 0.249642)
							(end 0.2794 0.1778)
						)
						(arc
							(start 0.2794 -0.1778)
							(mid 0.249642 -0.249642)
							(end 0.1778 -0.2794)
						)
					)
					(width 0)
					(fill yes)
				)
			)
		)
	)
	(footprint ""
		(layer "F.Cu")
		(at 42.8244 -107.7722 90)
		(property "Reference" "R421"
			(at 0 0 90)
			(layer "F.SilkS")
			(hide yes)
			(effects
				(font
					(size 1.27 1.27)
				)
			)
		)
		(property "Value" "0R2J-2-GP"
			(at 0.064008 -3.993896 90)
			(unlocked yes)
			(layer "F.Fab")
			(hide yes)
			(effects
				(font
					(size 1.016 1.016)
					(thickness 0.1524)
				)
			)
		)
		(property "Device Type" "R402H16"
			(at 0.064008 -5.517896 90)
			(unlocked yes)
			(layer "F.Fab")
			(hide yes)
			(effects
				(font
					(size 1.016 1.016)
					(thickness 0.1524)
				)
			)
		)
		(duplicate_pad_numbers_are_jumpers no)
		(fp_line
			(start 0.508 -0.9398)
			(end -0.508 -0.9398)
			(stroke
				(width 0.1524)
				(type default)
			)
			(layer "F.SilkS")
		)
		(fp_line
			(start -0.508 -0.9398)
			(end -0.508 0.9398)
			(stroke
				(width 0.1524)
				(type default)
			)
			(layer "F.SilkS")
		)
		(fp_rect
			(start -0.508 0.9398)
			(end 0.508 -0.9398)
			(stroke
				(width 0)
				(type default)
			)
			(fill no)
			(layer "F.CrtYd")
		)
		(fp_rect
			(start -0.508 0.9398)
			(end 0.508 -0.9398)
			(stroke
				(width 0)
				(type default)
			)
			(fill no)
			(layer "F.Fab")
		)
		(pad "1" smd custom
			(at 0 -0.4445 90)
			(size 0.1397 0.1397)
			(layers "F.Cu" "F.Mask" "F.Paste")
			(net "SW_HDD13_G")
			(options
				(clearance outline)
				(anchor circle)
			)
			(primitives
				(gr_poly
					(pts
						(arc
							(start -0.1778 -0.2794)
							(mid -0.249642 -0.249642)
							(end -0.2794 -0.1778)
						)
						(arc
							(start -0.2794 0.1778)
							(mid -0.249642 0.249642)
							(end -0.1778 0.2794)
						)
						(arc
							(start 0.1778 0.2794)
							(mid 0.249642 0.249642)
							(end 0.2794 0.1778)
						)
						(arc
							(start 0.2794 -0.1778)
							(mid 0.249642 -0.249642)
							(end 0.1778 -0.2794)
						)
					)
					(width 0)
					(fill yes)
				)
			)
		)
		(pad "2" smd custom
			(at 0 0.4445 90)
			(size 0.1397 0.1397)
			(layers "F.Cu" "F.Mask" "F.Paste")
			(net "SW_HDD13_R")
			(options
				(clearance outline)
				(anchor circle)
			)
			(primitives
				(gr_poly
					(pts
						(arc
							(start -0.1778 -0.2794)
							(mid -0.249642 -0.249642)
							(end -0.2794 -0.1778)
						)
						(arc
							(start -0.2794 0.1778)
							(mid -0.249642 0.249642)
							(end -0.1778 0.2794)
						)
						(arc
							(start 0.1778 0.2794)
							(mid 0.249642 0.249642)
							(end 0.2794 0.1778)
						)
						(arc
							(start 0.2794 -0.1778)
							(mid 0.249642 -0.249642)
							(end 0.1778 -0.2794)
						)
					)
					(width 0)
					(fill yes)
				)
			)
		)
	)
)
